# SCM (Grand Teton) — schematic netlist excerpt (pin names and nets, part order shuffled) for the footprints in the layout excerpt that follows; sources: Cadence DE-HDL packaged netlist, KiCad conversion of 12092022_DA0F0TMDCD0_F0T_Management_Board_D_brd_V3_OCP.brd

R455  Q_RES  33.2 1% CHIP  pkg 0402LF  page 10 : A = SMB_BMC_MM2_SCL ; B = SMB_BMC_MM2_SCL_R1
R45  Q_RES  4.7K 1% CHIP  pkg 0402LF  page 11 : A = P3V3_AUX ; B = FM_THROTTLE_N

(kicad_pcb
	(version 20260206)
	(generator "pcbnew")
	(generator_version "10.0")
	(general
		(thickness 1.6)
		(legacy_teardrops no)
	)
	(paper "A4")
	(title_block
		(title "12092022_DA0F0TMDCD0_F0T_Management_Board_D_brd_V3_OCP.brd")
		(comment 1 "Grand Teton / footprints 487-488 of 1440")
	)
	(layers
		(0 "F.Cu" signal "TOP")
		(4 "In1.Cu" signal "GND")
		(6 "In2.Cu" signal "IN1")
		(8 "In3.Cu" signal "GND1")
		(10 "In4.Cu" signal "IN2")
		(12 "In5.Cu" signal "VCC")
		(14 "In6.Cu" signal "VCC1")
		(16 "In7.Cu" signal "IN3")
		(18 "In8.Cu" signal "GND2")
		(20 "In9.Cu" signal "IN4")
		(22 "In10.Cu" signal "GND3")
		(2 "B.Cu" signal "BOTTOM")
		(9 "F.Adhes" user "F.Adhesive")
		(11 "B.Adhes" user "B.Adhesive")
		(13 "F.Paste" user "Package Geometry/Pastemask Top")
		(15 "B.Paste" user "Package Geometry/Pastemask Bottom")
		(5 "F.SilkS" user "Ref Des/Silkscreen Top")
		(7 "B.SilkS" user "Ref Des/Silkscreen Bottom")
		(1 "F.Mask" user "Board Geometry/Soldermask Top")
		(3 "B.Mask" user "Board Geometry/Soldermask Bottom")
		(17 "Dwgs.User" user "User.Drawings")
		(19 "Cmts.User" user "User.Comments")
		(21 "Eco1.User" user "User.Eco1")
		(23 "Eco2.User" user "User.Eco2")
		(25 "Edge.Cuts" user "Board Geometry/Outline")
		(27 "Margin" user)
		(31 "F.CrtYd" user "Package Geometry/Place Bound Top")
		(29 "B.CrtYd" user "Package Geometry/Place Bound Bottom")
		(35 "F.Fab" user "Ref Des/Assembly Top")
		(33 "B.Fab" user "Ref Des/Assembly Bottom")
	)
	(footprint ""
		(layer "F.Cu")
		(at 29.591 -102.7684 -90)
		(property "Reference" "R45"
			(at 0 0 270)
			(layer "F.SilkS")
			(hide yes)
			(effects
				(font
					(size 1.27 1.27)
				)
			)
		)
		(property "Value" ""
			(at 0 0 270)
			(layer "F.Fab")
			(effects
				(font
					(size 1.27 1.27)
				)
			)
		)
		(duplicate_pad_numbers_are_jumpers no)
		(fp_line
			(start -0.7874 0.4064)
			(end -0.7874 -0.4064)
			(stroke
				(width 0.1524)
				(type default)
			)
			(layer "F.SilkS")
		)
		(fp_line
			(start 0.7874 0.4064)
			(end -0.7874 0.4064)
			(stroke
				(width 0.1524)
				(type default)
			)
			(layer "F.SilkS")
		)
		(fp_line
			(start -0.7874 -0.4064)
			(end 0.7874 -0.4064)
			(stroke
				(width 0.1524)
				(type default)
			)
			(layer "F.SilkS")
		)
		(fp_line
			(start 0.7874 -0.4064)
			(end 0.7874 0.4064)
			(stroke
				(width 0.1524)
				(type default)
			)
			(layer "F.SilkS")
		)
		(fp_line
			(start -0.67945 0.3048)
			(end -0.67945 -0.305054)
			(stroke
				(width 0.1)
				(type default)
			)
			(layer "F.Fab")
		)
		(fp_line
			(start -0.12065 0.3048)
			(end -0.67945 0.3048)
			(stroke
				(width 0.1)
				(type default)
			)
			(layer "F.Fab")
		)
		(fp_line
			(start 0.120396 0.3048)
			(end 0.120396 0.2794)
			(stroke
				(width 0.1)
				(type default)
			)
			(layer "F.Fab")
		)
		(fp_line
			(start 0.67945 0.3048)
			(end 0.120396 0.3048)
			(stroke
				(width 0.1)
				(type default)
			)
			(layer "F.Fab")
		)
		(fp_line
			(start -0.12065 0.2794)
			(end -0.12065 0.3048)
			(stroke
				(width 0.1)
				(type default)
			)
			(layer "F.Fab")
		)
		(fp_line
			(start 0.120396 0.2794)
			(end -0.12065 0.2794)
			(stroke
				(width 0.1)
				(type default)
			)
			(layer "F.Fab")
		)
		(fp_line
			(start -0.12065 -0.2794)
			(end 0.12065 -0.2794)
			(stroke
				(width 0.1)
				(type default)
			)
			(layer "F.Fab")
		)
		(fp_line
			(start 0.12065 -0.2794)
			(end 0.12065 -0.3048)
			(stroke
				(width 0.1)
				(type default)
			)
			(layer "F.Fab")
		)
		(fp_line
			(start 0.12065 -0.3048)
			(end 0.67945 -0.3048)
			(stroke
				(width 0.1)
				(type default)
			)
			(layer "F.Fab")
		)
		(fp_line
			(start 0.67945 -0.3048)
			(end 0.67945 0.3048)
			(stroke
				(width 0.1)
				(type default)
			)
			(layer "F.Fab")
		)
		(fp_line
			(start -0.67945 -0.305054)
			(end -0.12065 -0.305054)
			(stroke
				(width 0.1)
				(type default)
			)
			(layer "F.Fab")
		)
		(fp_line
			(start -0.12065 -0.305054)
			(end -0.12065 -0.2794)
			(stroke
				(width 0.1)
				(type default)
			)
			(layer "F.Fab")
		)
		(pad "1" smd circle
			(at -0.40005 0 270)
			(size 0 0)
			(layers "F.Cu" "F.Mask" "F.Paste")
			(net "P3V3_AUX")
		)
		(pad "2" smd circle
			(at 0.40005 0 270)
			(size 0 0)
			(layers "F.Cu" "F.Mask" "F.Paste")
			(net "FM_THROTTLE_N")
		)
	)
	(footprint ""
		(layer "F.Cu")
		(at 41.7576 -30.861 90)
		(property "Reference" "R455"
			(at 0 0 90)
			(layer "F.SilkS")
			(hide yes)
			(effects
				(font
					(size 1.27 1.27)
				)
			)
		)
		(property "Value" ""
			(at 0 0 90)
			(layer "F.Fab")
			(effects
				(font
					(size 1.27 1.27)
				)
			)
		)
		(duplicate_pad_numbers_are_jumpers no)
		(fp_line
			(start 0.7874 -0.4064)
			(end 0.7874 0.4064)
			(stroke
				(width 0.1524)
				(type default)
			)
			(layer "F.SilkS")
		)
		(fp_line
			(start -0.7874 -0.4064)
			(end 0.7874 -0.4064)
			(stroke
				(width 0.1524)
				(type default)
			)
			(layer "F.SilkS")
		)
		(fp_line
			(start 0.7874 0.4064)
			(end -0.7874 0.4064)
			(stroke
				(width 0.1524)
				(type default)
			)
			(layer "F.SilkS")
		)
		(fp_line
			(start -0.7874 0.4064)
			(end -0.7874 -0.4064)
			(stroke
				(width 0.1524)
				(type default)
			)
			(layer "F.SilkS")
		)
		(fp_line
			(start -0.12065 -0.305054)
			(end -0.12065 -0.2794)
			(stroke
				(width 0.1)
				(type default)
			)
			(layer "F.Fab")
		)
		(fp_line
			(start -0.67945 -0.305054)
			(end -0.12065 -0.305054)
			(stroke
				(width 0.1)
				(type default)
			)
			(layer "F.Fab")
		)
		(fp_line
			(start 0.67945 -0.3048)
			(end 0.67945 0.3048)
			(stroke
				(width 0.1)
				(type default)
			)
			(layer "F.Fab")
		)
		(fp_line
			(start 0.12065 -0.3048)
			(end 0.67945 -0.3048)
			(stroke
				(width 0.1)
				(type default)
			)
			(layer "F.Fab")
		)
		(fp_line
			(start 0.12065 -0.2794)
			(end 0.12065 -0.3048)
			(stroke
				(width 0.1)
				(type default)
			)
			(layer "F.Fab")
		)
		(fp_line
			(start -0.12065 -0.2794)
			(end 0.12065 -0.2794)
			(stroke
				(width 0.1)
				(type default)
			)
			(layer "F.Fab")
		)
		(fp_line
			(start 0.120396 0.2794)
			(end -0.12065 0.2794)
			(stroke
				(width 0.1)
				(type default)
			)
			(layer "F.Fab")
		)
		(fp_line
			(start -0.12065 0.2794)
			(end -0.12065 0.3048)
			(stroke
				(width 0.1)
				(type default)
			)
			(layer "F.Fab")
		)
		(fp_line
			(start 0.67945 0.3048)
			(end 0.120396 0.3048)
			(stroke
				(width 0.1)
				(type default)
			)
			(layer "F.Fab")
		)
		(fp_line
			(start 0.120396 0.3048)
			(end 0.120396 0.2794)
			(stroke
				(width 0.1)
				(type default)
			)
			(layer "F.Fab")
		)
		(fp_line
			(start -0.12065 0.3048)
			(end -0.67945 0.3048)
			(stroke
				(width 0.1)
				(type default)
			)
			(layer "F.Fab")
		)
		(fp_line
			(start -0.67945 0.3048)
			(end -0.67945 -0.305054)
			(stroke
				(width 0.1)
				(type default)
			)
			(layer "F.Fab")
		)
		(pad "1" smd circle
			(at -0.40005 0 90)
			(size 0 0)
			(layers "F.Cu" "F.Mask" "F.Paste")
			(net "SMB_BMC_MM2_SCL")
		)
		(pad "2" smd circle
			(at 0.40005 0 90)
			(size 0 0)
			(layers "F.Cu" "F.Mask" "F.Paste")
			(net "SMB_BMC_MM2_SCL_R1")
		)
	)
)
